# T6G (Grand Teton) — schematic netlist excerpt (pin names and nets, part order shuffled) for the footprints in the layout excerpt that follows; sources: Cadence DE-HDL packaged netlist, KiCad conversion of 04192023_DAF0TMB3IC0_F0TG_MB_C_brd_V02_OCP.brd

J26  SCONN288_DDR506112002KQ  IO  pkg DDR288S_1-1VXC  page 99
  VIN_BULK0  = P12V_MEM_CPU1
  RFU0  = NC
  VIN_MGMT  = P3V3_AUX
  HSCL  = I3C_SPD_DDRB_CPU1_SCL
  HSDA  = I3C_SPD_DDRB_CPU1_SDA
  VSS0  = GND
  DQ0_A  = M_B_CPU1_SA_DQ<0>
  VSS1  = GND
  DQ1_A  = M_B_CPU1_SA_DQ<1>
  VSS2  = GND
  DQS0_A_T  = M_B_CPU1_SA_DQS_DP<0>
  DQS0_A_C  = M_B_CPU1_SA_DQS_DN<0>
  VSS3  = GND
  DQ4_A  = M_B_CPU1_SA_DQ<4>
  VSS4  = GND
  DQ5_A  = M_B_CPU1_SA_DQ<5>
  VSS5  = GND
  DQ8_A  = M_B_CPU1_SA_DQ<8>
  VSS6  = GND
  DQ9_A  = M_B_CPU1_SA_DQ<9>
  VSS7  = GND
  DQS1_A_T  = M_B_CPU1_SA_DQS_DP<1>
  DQS1_A_C  = M_B_CPU1_SA_DQS_DN<1>
  VSS8  = GND
  DQ12_A  = M_B_CPU1_SA_DQ<12>
  VSS9  = GND
  DQ13_A  = M_B_CPU1_SA_DQ<13>
  VSS10  = GND
  DQ16_A  = M_B_CPU1_SA_DQ<16>
  VSS11  = GND
  DQ17_A  = M_B_CPU1_SA_DQ<17>
  VSS12  = GND
  DQS2_A_T  = M_B_CPU1_SA_DQS_DP<2>
  DQS2_A_C  = M_B_CPU1_SA_DQS_DN<2>
  VSS13  = GND
  DQ20_A  = M_B_CPU1_SA_DQ<20>
  VSS14  = GND
  DQ21_A  = M_B_CPU1_SA_DQ<21>
  VSS15  = GND
  DQ24_A  = M_B_CPU1_SA_DQ<24>
  VSS16  = GND
  DQ25_A  = M_B_CPU1_SA_DQ<25>
  VSS17  = GND
  DQS3_A_T  = M_B_CPU1_SA_DQS_DP<3>
  DQS3_A_C  = M_B_CPU1_SA_DQS_DN<3>
  VSS18  = GND
  DQ28_A  = M_B_CPU1_SA_DQ<28>
  VSS19  = GND
  DQ29_A  = M_B_CPU1_SA_DQ<29>
  VSS20  = GND
  CB0_A  = M_B_CPU1_SA_CB<0>
  VSS21  = GND
  CB1_A  = M_B_CPU1_SA_CB<1>
  VSS22  = GND
  DQS4_A_T  = M_B_CPU1_SA_DQS_DP<4>
  DQS4_A_C  = M_B_CPU1_SA_DQS_DN<4>
  VSS23  = GND
  CB4_A  = M_B_CPU1_SA_CB<4>
  VSS24  = GND
  CB5_A  = M_B_CPU1_SA_CB<5>
  VSS25  = GND
  ALERT_N  = M_B_CPU1_ALERT_N
  VSS26  = GND
  CS0_A_N  = M_B_CPU1_SA_CS_N<0>
  VSS27  = GND
  CA0_A  = M_B_CPU1_SA_CA<0>
  VSS28  = GND
  CA2_A  = M_B_CPU1_SA_CA<2>
  VSS29  = GND
  CA4_A  = M_B_CPU1_SA_CA<4>
  VSS30  = GND
  CA6_A  = M_B_CPU1_SA_CA<6>
  VSS31  = GND
  PAR_A  = M_B_CPU1_SA_PAR
  VSS32  = GND
  CA0_B  = M_B_CPU1_SB_CA<0>
  VSS33  = GND
  CA2_B  = M_B_CPU1_SB_CA<2>
  VSS34  = GND
  CA4_B  = M_B_CPU1_SB_CA<4>
  VSS35  = GND
  CA6_B  = M_B_CPU1_SB_CA<6>
  VSS36  = GND
  CS0_B_N  = M_B_CPU1_SB_CS_N<0>
  VSS37  = GND
  \lbd||rsp_a_n\  = M_B_CPU1_SA_RSP<0>
  \lbs||rsp_b_n\  = M_B_CPU1_SB_RSP<0>
  VSS38  = GND
  CB4_B  = M_B_CPU1_SB_CB<4>
  VSS39  = GND
  CB5_B  = M_B_CPU1_SB_CB<5>
  VSS40  = GND
  \dqs9_b_t||tdqs9_b_t||dbi4_b_n\  = M_B_CPU1_SB_DQS_DP<9>
  \dqs9_b_c||tdqs9_b_c\  = M_B_CPU1_SB_DQS_DN<9>
  VSS41  = GND
  CB0_B  = M_B_CPU1_SB_CB<0>
  VSS42  = GND
  CB1_B  = M_B_CPU1_SB_CB<1>
  VSS43  = GND
  DQ0_B  = M_B_CPU1_SB_DQ<0>
  VSS44  = GND
  DQ1_B  = M_B_CPU1_SB_DQ<1>
  VSS45  = GND
  DQS0_B_T  = M_B_CPU1_SB_DQS_DP<0>
  DQS0_B_C  = M_B_CPU1_SB_DQS_DN<0>
  VSS46  = GND
  DQ4_B  = M_B_CPU1_SB_DQ<4>
  VSS47  = GND
  DQ5_B  = M_B_CPU1_SB_DQ<5>
  VSS48  = GND
  DQ8_B  = M_B_CPU1_SB_DQ<8>
  VSS49  = GND
  DQ9_B  = M_B_CPU1_SB_DQ<9>
  VSS50  = GND
  DQS1_B_T  = M_B_CPU1_SB_DQS_DP<1>
  DQS1_B_C  = M_B_CPU1_SB_DQS_DN<1>
  VSS51  = GND
  DQ12_B  = M_B_CPU1_SB_DQ<12>
  VSS52  = GND
  DQ13_B  = M_B_CPU1_SB_DQ<13>
  VSS53  = GND
  DQ16_B  = M_B_CPU1_SB_DQ<16>
  VSS54  = GND
  DQ17_B  = M_B_CPU1_SB_DQ<17>
  VSS55  = GND
  DQS2_B_T  = M_B_CPU1_SB_DQS_DP<2>
  DQS2_B_C  = M_B_CPU1_SB_DQS_DN<2>
  VSS56  = GND
  DQ20_B  = M_B_CPU1_SB_DQ<20>
  VSS57  = GND
  DQ21_B  = M_B_CPU1_SB_DQ<21>
  VSS58  = GND
  DQ24_B  = M_B_CPU1_SB_DQ<24>
  VSS59  = GND
  DQ25_B  = M_B_CPU1_SB_DQ<25>
  VSS60  = GND
  DQS3_B_T  = M_B_CPU1_SB_DQS_DP<3>
  DQS3_B_C  = M_B_CPU1_SB_DQS_DN<3>
  VSS61  = GND
  DQ28_B  = M_B_CPU1_SB_DQ<28>
  VSS62  = GND
  DQ29_B  = M_B_CPU1_SB_DQ<29>
  VSS63  = GND
  RFU1  = NC
  VIN_BULK1  = P12V_MEM_CPU1
  VIN_BULK2  = P12V_MEM_CPU1
  \pwr_good||fail_n\  = PWRGD_CHB_CPU1_DIMM
  HAS  = PD_CHB_CPU1_DIMM_SAA
  RFU2  = NC
  RFU3  = NC
  VSS64  = GND
  DQ2_A  = M_B_CPU1_SA_DQ<2>
  VSS65  = GND
  DQ3_A  = M_B_CPU1_SA_DQ<3>
  VSS66  = GND
  \dqs5_a_c||tdqs5_a_c||dqs5_a_t||tdqs5_a_t\  = M_B_CPU1_SA_DQS_DN<5>
  \dqs5_a_t||tdqs5_a_t\  = M_B_CPU1_SA_DQS_DP<5>
  VSS67  = GND
  DQ6_A  = M_B_CPU1_SA_DQ<6>
  VSS68  = GND
  DQ7_A  = M_B_CPU1_SA_DQ<7>
  VSS69  = GND
  DQ10_A  = M_B_CPU1_SA_DQ<10>
  VSS70  = GND
  DQ11_A  = M_B_CPU1_SA_DQ<11>
  VSS71  = GND
  \dqs6_a_c||tdqs6_a_c||dqs6_a_t||tdqs6_a_t\  = M_B_CPU1_SA_DQS_DN<6>
  \dqs6_a_t||tdqs6_a_t\  = M_B_CPU1_SA_DQS_DP<6>
  VSS72  = GND
  DQ14_A  = M_B_CPU1_SA_DQ<14>
  VSS73  = GND
  DQ15_A  = M_B_CPU1_SA_DQ<15>
  VSS74  = GND
  DQ18_A  = M_B_CPU1_SA_DQ<18>
  VSS75  = GND
  DQ19_A  = M_B_CPU1_SA_DQ<19>
  VSS76  = GND
  \dqs7_a_c||tdqs7_a_c\  = M_B_CPU1_SA_DQS_DN<7>
  \dqs7_a_t||tdqs7_a_t\  = M_B_CPU1_SA_DQS_DP<7>
  VSS77  = GND
  DQ22_A  = M_B_CPU1_SA_DQ<22>
  VSS78  = GND
  DQ23_A  = M_B_CPU1_SA_DQ<23>
  VSS79  = GND
  DQ26_A  = M_B_CPU1_SA_DQ<26>
  VSS80  = GND
  DQ27_A  = M_B_CPU1_SA_DQ<27>
  VSS81  = GND
  \dqs8_a_c||tdqs8_a_c\  = M_B_CPU1_SA_DQS_DN<8>
  \dqs8_a_t||tdqs8_a_t\  = M_B_CPU1_SA_DQS_DP<8>
  VSS82  = GND
  DQ30_A  = M_B_CPU1_SA_DQ<30>
  VSS83  = GND
  DQ31_A  = M_B_CPU1_SA_DQ<31>
  VSS84  = GND
  CB2_A  = M_B_CPU1_SA_CB<2>
  VSS85  = GND
  CB3_A  = M_B_CPU1_SA_CB<3>
  VSS86  = GND
  \dqs9_a_c||tdqs9_a_c\  = M_B_CPU1_SA_DQS_DN<9>
  \dqs9_a_t||tdqs9_a_t\  = M_B_CPU1_SA_DQS_DP<9>
  VSS87  = GND
  CB6_A  = M_B_CPU1_SA_CB<6>
  VSS88  = GND
  CB7_A  = M_B_CPU1_SA_CB<7>
  VSS89  = GND
  RESET_N  = M_B_CPU1_RESET_N
  VSS90  = GND
  CS1_A_N  = M_B_CPU1_SA_CS_N<1>
  VSS91  = GND
  CA1_A  = M_B_CPU1_SA_CA<1>
  VSS92  = GND
  CA3_A  = M_B_CPU1_SA_CA<3>
  VSS93  = GND
  CA5_A  = M_B_CPU1_SA_CA<5>
  VSS94  = GND
  CK_T  = M_B_CPU1_CLK_DP<0>
  CK_C  = M_B_CPU1_CLK_DN<0>
  VSS95  = GND
  RFU4  = NC
  CA1_B  = M_B_CPU1_SB_CA<1>
  VSS96  = GND
  CA3_B  = M_B_CPU1_SB_CA<3>
  VSS97  = GND
  CA5_B  = M_B_CPU1_SB_CA<5>
  VSS98  = GND
  PAR_B  = M_B_CPU1_SB_PAR
  VSS99  = GND
  CS1_B_N  = M_B_CPU1_SB_CS_N<1>
  VSS100  = GND
  RFU5  = NC
  RFU6  = NC
  VSS101  = GND
  CB6_B  = M_B_CPU1_SB_CB<6>
  VSS102  = GND
  CB7_B  = M_B_CPU1_SB_CB<7>
  VSS103  = GND
  DQS4_B_C  = M_B_CPU1_SB_DQS_DN<4>
  DQS4_B_T  = M_B_CPU1_SB_DQS_DP<4>
  VSS104  = GND
  CB2_B  = M_B_CPU1_SB_CB<2>
  VSS105  = GND
  CB3_B  = M_B_CPU1_SB_CB<3>
  VSS106  = GND
  DQ2_B  = M_B_CPU1_SB_DQ<2>
  VSS107  = GND
  DQ3_B  = M_B_CPU1_SB_DQ<3>
  VSS108  = GND
  \dqs5_b_c||tdqs5_b_c\  = M_B_CPU1_SB_DQS_DN<5>
  \dqs5_b_t||tdqs5_b_t\  = M_B_CPU1_SB_DQS_DP<5>
  VSS109  = GND
  DQ6_B  = M_B_CPU1_SB_DQ<6>
  VSS110  = GND
  DQ7_B  = M_B_CPU1_SB_DQ<7>
  VSS111  = GND
  DQ10_B  = M_B_CPU1_SB_DQ<10>
  VSS112  = GND
  DQ11_B  = M_B_CPU1_SB_DQ<11>
  VSS113  = GND
  \dqs6_b_c||tdqs6_b_c\  = M_B_CPU1_SB_DQS_DN<6>
  \dqs6_b_t||tdqs6_b_t\  = M_B_CPU1_SB_DQS_DP<6>
  VSS114  = GND
  DQ14_B  = M_B_CPU1_SB_DQ<14>
  VSS115  = GND
  DQ15_B  = M_B_CPU1_SB_DQ<15>
  VSS116  = GND
  DQ18_B  = M_B_CPU1_SB_DQ<18>
  VSS117  = GND
  DQ19_B  = M_B_CPU1_SB_DQ<19>
  VSS118  = GND
  \dqs7_b_c||tdqs7_b_c\  = M_B_CPU1_SB_DQS_DN<7>
  \dqs7_b_t||tdqs7_b_t\  = M_B_CPU1_SB_DQS_DP<7>
  VSS119  = GND
  DQ22_B  = M_B_CPU1_SB_DQ<22>
  VSS120  = GND
  DQ23_B  = M_B_CPU1_SB_DQ<23>
  VSS121  = GND
  DQ26_B  = M_B_CPU1_SB_DQ<26>
  VSS122  = GND
  DQ27_B  = M_B_CPU1_SB_DQ<27>
  VSS123  = GND
  \dqs8_b_c||tdqs8_b_c\  = M_B_CPU1_SB_DQS_DN<8>
  \dqs8_b_t||tdqs8_b_t\  = M_B_CPU1_SB_DQS_DP<8>
  VSS124  = GND
  DQ30_B  = M_B_CPU1_SB_DQ<30>
  VSS125  = GND
  DQ31_B  = M_B_CPU1_SB_DQ<31>
  VSS126  = GND
  G1  = GND
  G2  = GND
  G3  = GND

(kicad_pcb
	(version 20260206)
	(generator "pcbnew")
	(generator_version "10.0")
	(general
		(thickness 1.6)
		(legacy_teardrops no)
	)
	(paper "A4")
	(title_block
		(title "04192023_DAF0TMB3IC0_F0TG_MB_C_brd_V02_OCP.brd")
		(comment 1 "Grand Teton / footprint 4371 of 8354 (J26), pads 47-92 of 291")
	)
	(layers
		(0 "F.Cu" signal "TOP")
		(4 "In1.Cu" signal "GND")
		(6 "In2.Cu" signal "IN1")
		(8 "In3.Cu" signal "GND1")
		(10 "In4.Cu" signal "IN2")
		(12 "In5.Cu" signal "GND2")
		(14 "In6.Cu" signal "IN3")
		(16 "In7.Cu" signal "GND3")
		(18 "In8.Cu" signal "VCC")
		(20 "In9.Cu" signal "VCC1")
		(22 "In10.Cu" signal "GND4")
		(24 "In11.Cu" signal "IN4")
		(26 "In12.Cu" signal "GND5")
		(28 "In13.Cu" signal "IN5")
		(30 "In14.Cu" signal "GND6")
		(32 "In15.Cu" signal "IN6")
		(34 "In16.Cu" signal "GND7")
		(2 "B.Cu" signal "BOTTOM")
		(9 "F.Adhes" user "F.Adhesive")
		(11 "B.Adhes" user "B.Adhesive")
		(13 "F.Paste" user "Package Geometry/Pastemask Top")
		(15 "B.Paste" user "Package Geometry/Pastemask Bottom")
		(5 "F.SilkS" user "Ref Des/Silkscreen Top")
		(7 "B.SilkS" user "Ref Des/Silkscreen Bottom")
		(1 "F.Mask" user "Board Geometry/Soldermask Top")
		(3 "B.Mask" user "Board Geometry/Soldermask Bottom")
		(17 "Dwgs.User" user "User.Drawings")
		(19 "Cmts.User" user "User.Comments")
		(21 "Eco1.User" user "User.Eco1")
		(23 "Eco2.User" user "User.Eco2")
		(25 "Edge.Cuts" user "Board Geometry/Outline")
		(27 "Margin" user)
		(31 "F.CrtYd" user "Package Geometry/Place Bound Top")
		(29 "B.CrtYd" user "Package Geometry/Place Bound Bottom")
		(35 "F.Fab" user "Ref Des/Assembly Top")
		(33 "B.Fab" user "Ref Des/Assembly Bottom")
	)
	(footprint ""
		(layer "F.Cu")
		(at 49.834038 -255.560322 180)
		(property "Reference" "J26"
			(at -0.703326 -82.357722 0)
			(unlocked yes)
			(layer "F.SilkS")
			(effects
				(font
					(size 0.7874 0.5842)
					(thickness 0.1524)
				)
			)
		)
		(property "Value" ""
			(at 0 0 180)
			(layer "F.Fab")
			(effects
				(font
					(size 1.27 1.27)
				)
			)
		)
		(duplicate_pad_numbers_are_jumpers no)
		(pad "47" smd rect
			(at -2.050034 -24.224996 90)
			(size 0.519938 1.4986)
			(layers "F.Cu" "F.Mask" "F.Paste")
			(net "M_B_CPU1_SA_DQ<28>")
		)
		(pad "48" smd rect
			(at -2.050034 -23.375112 90)
			(size 0.519938 1.4986)
			(layers "F.Cu" "F.Mask" "F.Paste")
			(net "GND")
		)
		(pad "49" smd rect
			(at -2.050034 -22.524974 90)
			(size 0.519938 1.4986)
			(layers "F.Cu" "F.Mask" "F.Paste")
			(net "M_B_CPU1_SA_DQ<29>")
		)
		(pad "50" smd rect
			(at -2.050034 -21.67509 90)
			(size 0.519938 1.4986)
			(layers "F.Cu" "F.Mask" "F.Paste")
			(net "GND")
		)
		(pad "51" smd rect
			(at -2.050034 -20.824952 90)
			(size 0.519938 1.4986)
			(layers "F.Cu" "F.Mask" "F.Paste")
			(net "M_B_CPU1_SA_CB<0>")
		)
		(pad "52" smd rect
			(at -2.050034 -19.975068 90)
			(size 0.519938 1.4986)
			(layers "F.Cu" "F.Mask" "F.Paste")
			(net "GND")
		)
		(pad "53" smd rect
			(at -2.050034 -19.12493 90)
			(size 0.519938 1.4986)
			(layers "F.Cu" "F.Mask" "F.Paste")
			(net "M_B_CPU1_SA_CB<1>")
		)
		(pad "54" smd rect
			(at -2.050034 -18.275046 90)
			(size 0.519938 1.4986)
			(layers "F.Cu" "F.Mask" "F.Paste")
			(net "GND")
		)
		(pad "55" smd rect
			(at -2.050034 -17.424908 90)
			(size 0.519938 1.4986)
			(layers "F.Cu" "F.Mask" "F.Paste")
			(net "M_B_CPU1_SA_DQS_DP<4>")
		)
		(pad "56" smd rect
			(at -2.050034 -16.575024 90)
			(size 0.519938 1.4986)
			(layers "F.Cu" "F.Mask" "F.Paste")
			(net "M_B_CPU1_SA_DQS_DN<4>")
		)
		(pad "57" smd rect
			(at -2.050034 -15.724886 90)
			(size 0.519938 1.4986)
			(layers "F.Cu" "F.Mask" "F.Paste")
			(net "GND")
		)
		(pad "58" smd rect
			(at -2.050034 -14.875002 90)
			(size 0.519938 1.4986)
			(layers "F.Cu" "F.Mask" "F.Paste")
			(net "M_B_CPU1_SA_CB<4>")
		)
		(pad "59" smd rect
			(at -2.050034 -14.025118 90)
			(size 0.519938 1.4986)
			(layers "F.Cu" "F.Mask" "F.Paste")
			(net "GND")
		)
		(pad "60" smd rect
			(at -2.050034 -13.17498 90)
			(size 0.519938 1.4986)
			(layers "F.Cu" "F.Mask" "F.Paste")
			(net "M_B_CPU1_SA_CB<5>")
		)
		(pad "61" smd rect
			(at -2.050034 -12.325096 90)
			(size 0.519938 1.4986)
			(layers "F.Cu" "F.Mask" "F.Paste")
			(net "GND")
		)
		(pad "62" smd rect
			(at -2.050034 -11.474958 90)
			(size 0.519938 1.4986)
			(layers "F.Cu" "F.Mask" "F.Paste")
			(net "M_B_CPU1_ALERT_N")
		)
		(pad "63" smd rect
			(at -2.050034 -10.625074 90)
			(size 0.519938 1.4986)
			(layers "F.Cu" "F.Mask" "F.Paste")
			(net "GND")
		)
		(pad "64" smd rect
			(at -2.050034 -9.774936 90)
			(size 0.519938 1.4986)
			(layers "F.Cu" "F.Mask" "F.Paste")
			(net "M_B_CPU1_SA_CS_N<0>")
		)
		(pad "65" smd rect
			(at -2.050034 -8.925052 90)
			(size 0.519938 1.4986)
			(layers "F.Cu" "F.Mask" "F.Paste")
			(net "GND")
		)
		(pad "66" smd rect
			(at -2.050034 -8.074914 90)
			(size 0.519938 1.4986)
			(layers "F.Cu" "F.Mask" "F.Paste")
			(net "M_B_CPU1_SA_CA<0>")
		)
		(pad "67" smd rect
			(at -2.050034 -7.22503 90)
			(size 0.519938 1.4986)
			(layers "F.Cu" "F.Mask" "F.Paste")
			(net "GND")
		)
		(pad "68" smd rect
			(at -2.050034 -6.374892 90)
			(size 0.519938 1.4986)
			(layers "F.Cu" "F.Mask" "F.Paste")
			(net "M_B_CPU1_SA_CA<2>")
		)
		(pad "69" smd rect
			(at -2.050034 -5.525008 90)
			(size 0.519938 1.4986)
			(layers "F.Cu" "F.Mask" "F.Paste")
			(net "GND")
		)
		(pad "70" smd rect
			(at -2.050034 -4.675124 90)
			(size 0.519938 1.4986)
			(layers "F.Cu" "F.Mask" "F.Paste")
			(net "M_B_CPU1_SA_CA<4>")
		)
		(pad "71" smd rect
			(at -2.050034 -3.824986 90)
			(size 0.519938 1.4986)
			(layers "F.Cu" "F.Mask" "F.Paste")
			(net "GND")
		)
		(pad "72" smd rect
			(at -2.050034 -2.975102 90)
			(size 0.519938 1.4986)
			(layers "F.Cu" "F.Mask" "F.Paste")
			(net "M_B_CPU1_SA_CA<6>")
		)
		(pad "73" smd rect
			(at -2.050034 -2.124964 90)
			(size 0.519938 1.4986)
			(layers "F.Cu" "F.Mask" "F.Paste")
			(net "GND")
		)
		(pad "74" smd rect
			(at -2.050034 -1.27508 90)
			(size 0.519938 1.4986)
			(layers "F.Cu" "F.Mask" "F.Paste")
			(net "M_B_CPU1_SA_PAR")
		)
		(pad "75" smd rect
			(at -2.050034 -0.424942 90)
			(size 0.519938 1.4986)
			(layers "F.Cu" "F.Mask" "F.Paste")
			(net "GND")
		)
		(pad "76" smd rect
			(at -2.050034 5.525008 90)
			(size 0.519938 1.4986)
			(layers "F.Cu" "F.Mask" "F.Paste")
			(net "M_B_CPU1_SB_CA<0>")
		)
		(pad "77" smd rect
			(at -2.050034 6.374892 90)
			(size 0.519938 1.4986)
			(layers "F.Cu" "F.Mask" "F.Paste")
			(net "GND")
		)
		(pad "78" smd rect
			(at -2.050034 7.22503 90)
			(size 0.519938 1.4986)
			(layers "F.Cu" "F.Mask" "F.Paste")
			(net "M_B_CPU1_SB_CA<2>")
		)
		(pad "79" smd rect
			(at -2.050034 8.074914 90)
			(size 0.519938 1.4986)
			(layers "F.Cu" "F.Mask" "F.Paste")
			(net "GND")
		)
		(pad "80" smd rect
			(at -2.050034 8.925052 90)
			(size 0.519938 1.4986)
			(layers "F.Cu" "F.Mask" "F.Paste")
			(net "M_B_CPU1_SB_CA<4>")
		)
		(pad "81" smd rect
			(at -2.050034 9.774936 90)
			(size 0.519938 1.4986)
			(layers "F.Cu" "F.Mask" "F.Paste")
			(net "GND")
		)
		(pad "82" smd rect
			(at -2.050034 10.625074 90)
			(size 0.519938 1.4986)
			(layers "F.Cu" "F.Mask" "F.Paste")
			(net "M_B_CPU1_SB_CA<6>")
		)
		(pad "83" smd rect
			(at -2.050034 11.474958 90)
			(size 0.519938 1.4986)
			(layers "F.Cu" "F.Mask" "F.Paste")
			(net "GND")
		)
		(pad "84" smd rect
			(at -2.050034 12.325096 90)
			(size 0.519938 1.4986)
			(layers "F.Cu" "F.Mask" "F.Paste")
			(net "M_B_CPU1_SB_CS_N<0>")
		)
		(pad "85" smd rect
			(at -2.050034 13.17498 90)
			(size 0.519938 1.4986)
			(layers "F.Cu" "F.Mask" "F.Paste")
			(net "GND")
		)
		(pad "86" smd rect
			(at -2.050034 14.025118 90)
			(size 0.519938 1.4986)
			(layers "F.Cu" "F.Mask" "F.Paste")
			(net "M_B_CPU1_SA_RSP<0>")
		)
		(pad "87" smd rect
			(at -2.050034 14.875002 90)
			(size 0.519938 1.4986)
			(layers "F.Cu" "F.Mask" "F.Paste")
			(net "M_B_CPU1_SB_RSP<0>")
		)
		(pad "88" smd rect
			(at -2.050034 15.724886 90)
			(size 0.519938 1.4986)
			(layers "F.Cu" "F.Mask" "F.Paste")
			(net "GND")
		)
		(pad "89" smd rect
			(at -2.050034 16.575024 90)
			(size 0.519938 1.4986)
			(layers "F.Cu" "F.Mask" "F.Paste")
			(net "M_B_CPU1_SB_CB<4>")
		)
		(pad "90" smd rect
			(at -2.050034 17.424908 90)
			(size 0.519938 1.4986)
			(layers "F.Cu" "F.Mask" "F.Paste")
			(net "GND")
		)
		(pad "91" smd rect
			(at -2.050034 18.275046 90)
			(size 0.519938 1.4986)
			(layers "F.Cu" "F.Mask" "F.Paste")
			(net "M_B_CPU1_SB_CB<5>")
		)
		(pad "92" smd rect
			(at -2.050034 19.12493 90)
			(size 0.519938 1.4986)
			(layers "F.Cu" "F.Mask" "F.Paste")
			(net "GND")
		)
	)
)
